# T6G (Grand Teton) — schematic netlist excerpt (pin names and nets, part order shuffled) for the footprints in the layout excerpt that follows; sources: Cadence DE-HDL packaged netlist, KiCad conversion of 04192023_DAF0TMB3IC0_F0TG_MB_C_brd_V02_OCP.brd

PC628_3  Q_CAP  22UF 16V 20% X6S  pkg C0805  page 223 : A = SW_P12V_AUX_PVDDIO_P1_FLT ; B = GND

PQ13  MOSFET_PCH_GDS_ESD_PROTECTED  PJA3415AE IC  pkg SOT23_GDSXC  page 193
  D  = PVDDCR_SOC_P0_EN//ADDR_CFG
  G  = PVDDCR_SOC_P0_EN_GD
  S  = P3V3_AUX

PC212_2  Q_CAP  22UF 16V 20% X6S  pkg C0805  page 208 : A = SW_P12V_AUX_PVDD11_S3_P0_FLT ; B = GND

(kicad_pcb
	(version 20260206)
	(generator "pcbnew")
	(generator_version "10.0")
	(general
		(thickness 1.6)
		(legacy_teardrops no)
	)
	(paper "A4")
	(title_block
		(title "04192023_DAF0TMB3IC0_F0TG_MB_C_brd_V02_OCP.brd")
		(comment 1 "Grand Teton / footprints 4974-4976 of 8354")
	)
	(layers
		(0 "F.Cu" signal "TOP")
		(4 "In1.Cu" signal "GND")
		(6 "In2.Cu" signal "IN1")
		(8 "In3.Cu" signal "GND1")
		(10 "In4.Cu" signal "IN2")
		(12 "In5.Cu" signal "GND2")
		(14 "In6.Cu" signal "IN3")
		(16 "In7.Cu" signal "GND3")
		(18 "In8.Cu" signal "VCC")
		(20 "In9.Cu" signal "VCC1")
		(22 "In10.Cu" signal "GND4")
		(24 "In11.Cu" signal "IN4")
		(26 "In12.Cu" signal "GND5")
		(28 "In13.Cu" signal "IN5")
		(30 "In14.Cu" signal "GND6")
		(32 "In15.Cu" signal "IN6")
		(34 "In16.Cu" signal "GND7")
		(2 "B.Cu" signal "BOTTOM")
		(9 "F.Adhes" user "F.Adhesive")
		(11 "B.Adhes" user "B.Adhesive")
		(13 "F.Paste" user "Package Geometry/Pastemask Top")
		(15 "B.Paste" user "Package Geometry/Pastemask Bottom")
		(5 "F.SilkS" user "Ref Des/Silkscreen Top")
		(7 "B.SilkS" user "Ref Des/Silkscreen Bottom")
		(1 "F.Mask" user "Board Geometry/Soldermask Top")
		(3 "B.Mask" user "Board Geometry/Soldermask Bottom")
		(17 "Dwgs.User" user "User.Drawings")
		(19 "Cmts.User" user "User.Comments")
		(21 "Eco1.User" user "User.Eco1")
		(23 "Eco2.User" user "User.Eco2")
		(25 "Edge.Cuts" user "Board Geometry/Outline")
		(27 "Margin" user)
		(31 "F.CrtYd" user "Package Geometry/Place Bound Top")
		(29 "B.CrtYd" user "Package Geometry/Place Bound Bottom")
		(35 "F.Fab" user "Ref Des/Assembly Top")
		(33 "B.Fab" user "Ref Des/Assembly Bottom")
	)
	(footprint ""
		(layer "B.Cu")
		(at 367.595658 -145.495772 -90)
		(property "Reference" "PQ13"
			(at 1.50114 2.67335 270)
			(unlocked yes)
			(layer "B.SilkS")
			(effects
				(font
					(size 0.7874 0.5842)
					(thickness 0.1524)
				)
				(justify left mirror)
			)
		)
		(property "Value" ""
			(at 0 0 90)
			(layer "B.Fab")
			(effects
				(font
					(size 1.27 1.27)
				)
				(justify mirror)
			)
		)
		(duplicate_pad_numbers_are_jumpers no)
		(fp_line
			(start -1.603248 1.500124)
			(end 1.603248 1.500124)
			(stroke
				(width 0.1524)
				(type default)
			)
			(layer "B.SilkS")
		)
		(fp_line
			(start 1.603248 1.500124)
			(end 1.603248 -1.500124)
			(stroke
				(width 0.1524)
				(type default)
			)
			(layer "B.SilkS")
		)
		(fp_line
			(start -1.603248 -1.500124)
			(end -1.603248 1.500124)
			(stroke
				(width 0.1524)
				(type default)
			)
			(layer "B.SilkS")
		)
		(fp_line
			(start 1.603248 -1.500124)
			(end -1.603248 -1.500124)
			(stroke
				(width 0.1524)
				(type default)
			)
			(layer "B.SilkS")
		)
		(fp_line
			(start -0.700024 1.500124)
			(end -0.700024 0.219964)
			(stroke
				(width 0.1)
				(type default)
			)
			(layer "B.Fab")
		)
		(fp_line
			(start 0.700024 1.500124)
			(end -0.700024 1.500124)
			(stroke
				(width 0.1)
				(type default)
			)
			(layer "B.Fab")
		)
		(fp_line
			(start 0.700024 1.169924)
			(end 0.700024 1.500124)
			(stroke
				(width 0.1)
				(type default)
			)
			(layer "B.Fab")
		)
		(fp_line
			(start 1.249934 1.169924)
			(end 0.700024 1.169924)
			(stroke
				(width 0.1)
				(type default)
			)
			(layer "B.Fab")
		)
		(fp_line
			(start 0.6985 0.729996)
			(end 1.249934 0.729996)
			(stroke
				(width 0.1)
				(type default)
			)
			(layer "B.Fab")
		)
		(fp_line
			(start 1.249934 0.729996)
			(end 1.249934 1.169924)
			(stroke
				(width 0.1)
				(type default)
			)
			(layer "B.Fab")
		)
		(fp_line
			(start -1.249934 0.219964)
			(end -1.249934 -0.219964)
			(stroke
				(width 0.1)
				(type default)
			)
			(layer "B.Fab")
		)
		(fp_line
			(start -0.700024 0.219964)
			(end -1.249934 0.219964)
			(stroke
				(width 0.1)
				(type default)
			)
			(layer "B.Fab")
		)
		(fp_line
			(start -1.249934 -0.219964)
			(end -0.700024 -0.219964)
			(stroke
				(width 0.1)
				(type default)
			)
			(layer "B.Fab")
		)
		(fp_line
			(start -0.700024 -0.219964)
			(end -0.700024 -1.500124)
			(stroke
				(width 0.1)
				(type default)
			)
			(layer "B.Fab")
		)
		(fp_line
			(start 0.6985 -0.729996)
			(end 0.6985 0.729996)
			(stroke
				(width 0.1)
				(type default)
			)
			(layer "B.Fab")
		)
		(fp_line
			(start 1.249934 -0.729996)
			(end 0.6985 -0.729996)
			(stroke
				(width 0.1)
				(type default)
			)
			(layer "B.Fab")
		)
		(fp_line
			(start 0.700024 -1.169924)
			(end 1.249934 -1.169924)
			(stroke
				(width 0.1)
				(type default)
			)
			(layer "B.Fab")
		)
		(fp_line
			(start 1.249934 -1.169924)
			(end 1.249934 -0.729996)
			(stroke
				(width 0.1)
				(type default)
			)
			(layer "B.Fab")
		)
		(fp_line
			(start -0.700024 -1.500124)
			(end 0.700024 -1.500124)
			(stroke
				(width 0.1)
				(type default)
			)
			(layer "B.Fab")
		)
		(fp_line
			(start 0.700024 -1.500124)
			(end 0.700024 -1.169924)
			(stroke
				(width 0.1)
				(type default)
			)
			(layer "B.Fab")
		)
		(fp_rect
			(start 0.700024 1.500124)
			(end -0.700024 -1.500124)
			(stroke
				(width 0)
				(type default)
			)
			(fill no)
			(layer "B.Fab")
		)
		(pad "D" smd rect
			(at -0.999998 0 180)
			(size 0.8128 0.9144)
			(layers "B.Cu" "B.Mask" "B.Paste")
			(net "PVDDCR_SOC_P0_EN//ADDR_CFG")
		)
		(pad "G" smd rect
			(at 0.999998 -0.94996 180)
			(size 0.8128 0.9144)
			(layers "B.Cu" "B.Mask" "B.Paste")
			(net "PVDDCR_SOC_P0_EN_GD")
		)
		(pad "S" smd rect
			(at 0.999998 0.94996 180)
			(size 0.8128 0.9144)
			(layers "B.Cu" "B.Mask" "B.Paste")
			(net "P3V3_AUX")
		)
	)
	(footprint ""
		(layer "B.Cu")
		(at 435.029102 -351.058226 90)
		(property "Reference" "PC212_2"
			(at 0 0 90)
			(layer "B.SilkS")
			(hide yes)
			(effects
				(font
					(size 1.27 1.27)
				)
				(justify mirror)
			)
		)
		(property "Value" ""
			(at 0 0 90)
			(layer "B.Fab")
			(effects
				(font
					(size 1.27 1.27)
				)
				(justify mirror)
			)
		)
		(duplicate_pad_numbers_are_jumpers no)
		(fp_line
			(start 1.524 -0.762)
			(end -1.524 -0.762)
			(stroke
				(width 0.1524)
				(type default)
			)
			(layer "B.SilkS")
		)
		(fp_line
			(start -1.524 -0.762)
			(end -1.524 0.762)
			(stroke
				(width 0.1524)
				(type default)
			)
			(layer "B.SilkS")
		)
		(fp_line
			(start 1.524 0.762)
			(end 1.524 -0.762)
			(stroke
				(width 0.1524)
				(type default)
			)
			(layer "B.SilkS")
		)
		(fp_line
			(start -1.524 0.762)
			(end 1.524 0.762)
			(stroke
				(width 0.1524)
				(type default)
			)
			(layer "B.SilkS")
		)
		(fp_line
			(start 1.1049 -0.724916)
			(end 1.1049 0.724916)
			(stroke
				(width 0.1)
				(type default)
			)
			(layer "B.Fab")
		)
		(fp_line
			(start -1.1049 -0.724916)
			(end 1.1049 -0.724916)
			(stroke
				(width 0.1)
				(type default)
			)
			(layer "B.Fab")
		)
		(fp_line
			(start 1.1049 0.724916)
			(end -1.1049 0.724916)
			(stroke
				(width 0.1)
				(type default)
			)
			(layer "B.Fab")
		)
		(fp_line
			(start -1.1049 0.724916)
			(end -1.1049 -0.724916)
			(stroke
				(width 0.1)
				(type default)
			)
			(layer "B.Fab")
		)
		(pad "1" smd rect
			(at 0.889 0 90)
			(size 1.016 1.27)
			(layers "B.Cu" "B.Mask" "B.Paste")
			(net "SW_P12V_AUX_PVDD11_S3_P0_FLT")
		)
		(pad "2" smd rect
			(at -0.889 0 90)
			(size 1.016 1.27)
			(layers "B.Cu" "B.Mask" "B.Paste")
			(net "GND")
		)
	)
	(footprint ""
		(layer "B.Cu")
		(at 38.002718 -350.660716 -90)
		(property "Reference" "PC628_3"
			(at 0 0 90)
			(layer "B.SilkS")
			(hide yes)
			(effects
				(font
					(size 1.27 1.27)
				)
				(justify mirror)
			)
		)
		(property "Value" ""
			(at 0 0 90)
			(layer "B.Fab")
			(effects
				(font
					(size 1.27 1.27)
				)
				(justify mirror)
			)
		)
		(duplicate_pad_numbers_are_jumpers no)
		(fp_line
			(start -1.524 0.762)
			(end 1.524 0.762)
			(stroke
				(width 0.1524)
				(type default)
			)
			(layer "B.SilkS")
		)
		(fp_line
			(start 1.524 0.762)
			(end 1.524 -0.762)
			(stroke
				(width 0.1524)
				(type default)
			)
			(layer "B.SilkS")
		)
		(fp_line
			(start -1.524 -0.762)
			(end -1.524 0.762)
			(stroke
				(width 0.1524)
				(type default)
			)
			(layer "B.SilkS")
		)
		(fp_line
			(start 1.524 -0.762)
			(end -1.524 -0.762)
			(stroke
				(width 0.1524)
				(type default)
			)
			(layer "B.SilkS")
		)
		(fp_line
			(start -1.1049 0.724916)
			(end -1.1049 -0.724916)
			(stroke
				(width 0.1)
				(type default)
			)
			(layer "B.Fab")
		)
		(fp_line
			(start 1.1049 0.724916)
			(end -1.1049 0.724916)
			(stroke
				(width 0.1)
				(type default)
			)
			(layer "B.Fab")
		)
		(fp_line
			(start -1.1049 -0.724916)
			(end 1.1049 -0.724916)
			(stroke
				(width 0.1)
				(type default)
			)
			(layer "B.Fab")
		)
		(fp_line
			(start 1.1049 -0.724916)
			(end 1.1049 0.724916)
			(stroke
				(width 0.1)
				(type default)
			)
			(layer "B.Fab")
		)
		(pad "1" smd rect
			(at 0.889 0 270)
			(size 1.016 1.27)
			(layers "B.Cu" "B.Mask" "B.Paste")
			(net "SW_P12V_AUX_PVDDIO_P1_FLT")
		)
		(pad "2" smd rect
			(at -0.889 0 270)
			(size 1.016 1.27)
			(layers "B.Cu" "B.Mask" "B.Paste")
			(net "GND")
		)
	)
)
